(kicad_pcb
	(version 20260206)
	(generator "pcbnew")
	(generator_version "10.0")
	(general
		(thickness 1.6)
		(legacy_teardrops no)
	)
	(paper "A4")
	(title_block
		(title "Bryce Canyon_R.DPB_16317-1_OCP.brd")
		(comment 1 "Bryce Canyon / footprints 610-616 of 2099")
	)
	(layers
		(0 "F.Cu" signal "TOP")
		(4 "In1.Cu" signal "L2GND")
		(6 "In2.Cu" signal "L3")
		(8 "In3.Cu" signal "L4VCC")
		(10 "In4.Cu" signal "L5VCC")
		(12 "In5.Cu" signal "L6")
		(14 "In6.Cu" signal "L7GND")
		(2 "B.Cu" signal "BOTTOM")
		(9 "F.Adhes" user "F.Adhesive")
		(11 "B.Adhes" user "B.Adhesive")
		(13 "F.Paste" user "Package Geometry/Pastemask Top")
		(15 "B.Paste" user "Package Geometry/Pastemask Bottom")
		(5 "F.SilkS" user "Ref Des/Silkscreen Top")
		(7 "B.SilkS" user "Ref Des/Silkscreen Bottom")
		(1 "F.Mask" user "Board Geometry/Soldermask Top")
		(3 "B.Mask" user "Board Geometry/Soldermask Bottom")
		(17 "Dwgs.User" user "User.Drawings")
		(19 "Cmts.User" user "User.Comments")
		(21 "Eco1.User" user "User.Eco1")
		(23 "Eco2.User" user "User.Eco2")
		(25 "Edge.Cuts" user "Board Geometry/Outline")
		(27 "Margin" user)
		(31 "F.CrtYd" user "Package Geometry/Place Bound Top")
		(29 "B.CrtYd" user "Package Geometry/Place Bound Bottom")
		(35 "F.Fab" user "Ref Des/Assembly Top")
		(33 "B.Fab" user "Ref Des/Assembly Bottom")
	)
	(footprint ""
		(layer "F.Cu")
		(at 33.949894 -8.330184 180)
		(property "Reference" "U15"
			(at 0 0 180)
			(layer "F.SilkS")
			(hide yes)
			(effects
				(font
					(size 1.27 1.27)
				)
			)
		)
		(property "Value" "TMP75AIDGKR-GP"
			(at -0.1143 -9.1948 180)
			(unlocked yes)
			(layer "F.Fab")
			(hide yes)
			(effects
				(font
					(size 1.016 1.016)
					(thickness 0.1524)
				)
			)
		)
		(property "Device Type" "MSOP8-1H44"
			(at -0.1143 -10.795 180)
			(unlocked yes)
			(layer "F.Fab")
			(hide yes)
			(effects
				(font
					(size 1.016 1.016)
					(thickness 0.1524)
				)
			)
		)
		(duplicate_pad_numbers_are_jumpers no)
		(fp_line
			(start 1.0795 1.016)
			(end 1.0795 -1.016)
			(stroke
				(width 0.1524)
				(type default)
			)
			(layer "F.SilkS")
		)
		(fp_line
			(start 1.0795 -1.016)
			(end -1.9558 -1.016)
			(stroke
				(width 0.1524)
				(type default)
			)
			(layer "F.SilkS")
		)
		(fp_line
			(start -1.4478 -0.0381)
			(end -1.9558 0.4699)
			(stroke
				(width 0.1524)
				(type default)
			)
			(layer "F.SilkS")
		)
		(fp_line
			(start -1.778 1.0922)
			(end -1.778 3.048)
			(stroke
				(width 0.508)
				(type default)
			)
			(layer "F.SilkS")
		)
		(fp_line
			(start -1.9558 1.016)
			(end 1.0795 1.016)
			(stroke
				(width 0.1524)
				(type default)
			)
			(layer "F.SilkS")
		)
		(fp_line
			(start -1.9558 -0.5461)
			(end -1.4478 -0.0381)
			(stroke
				(width 0.1524)
				(type default)
			)
			(layer "F.SilkS")
		)
		(fp_line
			(start -1.9558 -1.016)
			(end -1.9558 1.016)
			(stroke
				(width 0.1524)
				(type default)
			)
			(layer "F.SilkS")
		)
		(fp_poly
			(pts
				(xy -1.1557 -1.016) (xy -1.1557 1.016) (xy 1.1557 1.016) (xy 1.1557 -1.016)
			)
			(stroke
				(width 0)
				(type default)
			)
			(fill yes)
			(layer "F.SilkS")
		)
		(fp_rect
			(start -1.4986 2.4511)
			(end 1.4986 -2.4511)
			(stroke
				(width 0)
				(type default)
			)
			(fill no)
			(layer "F.CrtYd")
		)
		(fp_poly
			(pts
				(xy -2.032 3.302) (xy -2.032 -3.302) (xy 2.032 -3.302) (xy 2.032 -2.1209) (xy 1.4986 -2.1209) (xy 1.4986 -2.4511)
				(xy -1.4986 -2.4511) (xy -1.4986 2.4511) (xy 1.4986 2.4511) (xy 1.4986 -2.1082) (xy 2.032 -2.1082)
				(xy 2.032 3.302)
			)
			(stroke
				(width 0)
				(type default)
			)
			(fill no)
			(layer "F.CrtYd")
		)
		(fp_rect
			(start -2.032 3.302)
			(end 2.032 -3.302)
			(stroke
				(width 0)
				(type default)
			)
			(fill no)
			(layer "F.Fab")
		)
		(pad "1" smd rect
			(at -0.97536 2.05486 180)
			(size 0.3556 1.524)
			(layers "F.Cu" "F.Mask" "F.Paste")
			(net "TEMP1_SDA")
		)
		(pad "2" smd rect
			(at -0.32512 2.05486 180)
			(size 0.3556 1.524)
			(layers "F.Cu" "F.Mask" "F.Paste")
			(net "TEMP1_SCL")
		)
		(pad "3" smd rect
			(at 0.32512 2.05486 180)
			(size 0.3556 1.524)
			(layers "F.Cu" "F.Mask" "F.Paste")
			(net "TEMP1_ALERT")
		)
		(pad "4" smd rect
			(at 0.97536 2.05486 180)
			(size 0.3556 1.524)
			(layers "F.Cu" "F.Mask" "F.Paste")
			(net "GND")
		)
		(pad "5" smd rect
			(at 0.97536 -2.05486 180)
			(size 0.3556 1.524)
			(layers "F.Cu" "F.Mask" "F.Paste")
			(net "TEMP1_A2")
		)
		(pad "6" smd rect
			(at 0.32512 -2.05486 180)
			(size 0.3556 1.524)
			(layers "F.Cu" "F.Mask" "F.Paste")
			(net "TEMP1_A1")
		)
		(pad "7" smd rect
			(at -0.32512 -2.05486 180)
			(size 0.3556 1.524)
			(layers "F.Cu" "F.Mask" "F.Paste")
			(net "TEMP1_A0")
		)
		(pad "8" smd rect
			(at -0.97536 -2.05486 180)
			(size 0.3556 1.524)
			(layers "F.Cu" "F.Mask" "F.Paste")
			(net "P3V3_STBY_A")
		)
	)
	(footprint ""
		(layer "F.Cu")
		(at 447.421 -147.193 -90)
		(property "Reference" "C318"
			(at 0 0 270)
			(layer "F.SilkS")
			(hide yes)
			(effects
				(font
					(size 1.27 1.27)
				)
			)
		)
		(property "Value" "SCD01U50V2KX-1GP"
			(at 1.1811 -2.7051 270)
			(unlocked yes)
			(layer "F.Fab")
			(hide yes)
			(effects
				(font
					(size 1.016 1.016)
					(thickness 0.1524)
				)
			)
		)
		(property "Device Type" "C402H22"
			(at 1.1811 -4.2291 270)
			(unlocked yes)
			(layer "F.Fab")
			(hide yes)
			(effects
				(font
					(size 1.016 1.016)
					(thickness 0.1524)
				)
			)
		)
		(duplicate_pad_numbers_are_jumpers no)
		(fp_rect
			(start -0.4318 0.9525)
			(end 0.4318 -0.9525)
			(stroke
				(width 0)
				(type default)
			)
			(fill no)
			(layer "F.CrtYd")
		)
		(fp_rect
			(start -0.4318 0.9525)
			(end 0.4318 -0.9525)
			(stroke
				(width 0)
				(type default)
			)
			(fill no)
			(layer "F.Fab")
		)
		(pad "1" smd custom
			(at 0 -0.4445 270)
			(size 0.1524 0.1524)
			(layers "F.Cu" "F.Mask" "F.Paste")
			(net "HDD_PRSNT_22")
			(options
				(clearance outline)
				(anchor circle)
			)
			(primitives
				(gr_poly
					(pts
						(arc
							(start 0.3048 -0.2032)
							(mid 0.275042 -0.275042)
							(end 0.2032 -0.3048)
						)
						(arc
							(start -0.2032 -0.3048)
							(mid -0.275042 -0.275042)
							(end -0.3048 -0.2032)
						)
						(arc
							(start -0.3048 0.2032)
							(mid -0.275042 0.275042)
							(end -0.2032 0.3048)
						)
						(arc
							(start 0.2032 0.3048)
							(mid 0.275042 0.275042)
							(end 0.3048 0.2032)
						)
					)
					(width 0)
					(fill yes)
				)
			)
		)
		(pad "2" smd custom
			(at 0 0.4445 270)
			(size 0.1524 0.1524)
			(layers "F.Cu" "F.Mask" "F.Paste")
			(net "GND")
			(options
				(clearance outline)
				(anchor circle)
			)
			(primitives
				(gr_poly
					(pts
						(arc
							(start 0.3048 -0.2032)
							(mid 0.275042 -0.275042)
							(end 0.2032 -0.3048)
						)
						(arc
							(start -0.2032 -0.3048)
							(mid -0.275042 -0.275042)
							(end -0.3048 -0.2032)
						)
						(arc
							(start -0.3048 0.2032)
							(mid -0.275042 0.275042)
							(end -0.2032 0.3048)
						)
						(arc
							(start 0.2032 0.3048)
							(mid 0.275042 0.275042)
							(end 0.3048 0.2032)
						)
					)
					(width 0)
					(fill yes)
				)
			)
		)
	)
	(footprint ""
		(layer "F.Cu")
		(at 114.9096 -148.717 -90)
		(property "Reference" "C225"
			(at 0 0 270)
			(layer "F.SilkS")
			(hide yes)
			(effects
				(font
					(size 1.27 1.27)
				)
			)
		)
		(property "Value" "SC1U16V3KX-5GP"
			(at 0 -2.8194 270)
			(unlocked yes)
			(layer "F.Fab")
			(hide yes)
			(effects
				(font
					(size 1.016 1.016)
					(thickness 0.1524)
				)
			)
		)
		(property "Device Type" "C603H36"
			(at 0 -4.3434 270)
			(unlocked yes)
			(layer "F.Fab")
			(hide yes)
			(effects
				(font
					(size 1.016 1.016)
					(thickness 0.1524)
				)
			)
		)
		(duplicate_pad_numbers_are_jumpers no)
		(fp_line
			(start 0.508 0)
			(end -0.508 0)
			(stroke
				(width 0.2032)
				(type default)
			)
			(layer "F.SilkS")
		)
		(fp_rect
			(start -0.5842 1.3335)
			(end 0.5842 -1.3335)
			(stroke
				(width 0)
				(type default)
			)
			(fill no)
			(layer "F.CrtYd")
		)
		(fp_rect
			(start -0.5842 1.3335)
			(end 0.5842 -1.3335)
			(stroke
				(width 0)
				(type default)
			)
			(fill no)
			(layer "F.Fab")
		)
		(pad "1" smd custom
			(at 0 -0.762 270)
			(size 0.2159 0.2159)
			(layers "F.Cu" "F.Mask" "F.Paste")
			(net "P5V_HDD15")
			(options
				(clearance outline)
				(anchor circle)
			)
			(primitives
				(gr_poly
					(pts
						(arc
							(start -0.3302 -0.4318)
							(mid -0.402042 -0.402042)
							(end -0.4318 -0.3302)
						)
						(arc
							(start -0.4318 0.3302)
							(mid -0.402042 0.402042)
							(end -0.3302 0.4318)
						)
						(arc
							(start 0.3302 0.4318)
							(mid 0.402042 0.402042)
							(end 0.4318 0.3302)
						)
						(arc
							(start 0.4318 -0.3302)
							(mid 0.402042 -0.402042)
							(end 0.3302 -0.4318)
						)
					)
					(width 0)
					(fill yes)
				)
			)
		)
		(pad "2" smd custom
			(at 0 0.762 270)
			(size 0.2159 0.2159)
			(layers "F.Cu" "F.Mask" "F.Paste")
			(net "GND")
			(options
				(clearance outline)
				(anchor circle)
			)
			(primitives
				(gr_poly
					(pts
						(arc
							(start -0.3302 -0.4318)
							(mid -0.402042 -0.402042)
							(end -0.4318 -0.3302)
						)
						(arc
							(start -0.4318 0.3302)
							(mid -0.402042 0.402042)
							(end -0.3302 0.4318)
						)
						(arc
							(start 0.3302 0.4318)
							(mid 0.402042 0.402042)
							(end 0.4318 0.3302)
						)
						(arc
							(start 0.4318 -0.3302)
							(mid 0.402042 -0.402042)
							(end 0.3302 -0.4318)
						)
					)
					(width 0)
					(fill yes)
				)
			)
		)
	)
	(footprint ""
		(layer "F.Cu")
		(at 54.61 -249.555 90)
		(property "Reference" "R183"
			(at 0 0 90)
			(layer "F.SilkS")
			(hide yes)
			(effects
				(font
					(size 1.27 1.27)
				)
			)
		)
		(property "Value" "4K7R2F-GP"
			(at 0.064008 -3.993896 90)
			(unlocked yes)
			(layer "F.Fab")
			(hide yes)
			(effects
				(font
					(size 1.016 1.016)
					(thickness 0.1524)
				)
			)
		)
		(property "Device Type" "R402H16"
			(at 0.064008 -5.517896 90)
			(unlocked yes)
			(layer "F.Fab")
			(hide yes)
			(effects
				(font
					(size 1.016 1.016)
					(thickness 0.1524)
				)
			)
		)
		(duplicate_pad_numbers_are_jumpers no)
		(fp_line
			(start 0.508 -0.9398)
			(end -0.508 -0.9398)
			(stroke
				(width 0.1524)
				(type default)
			)
			(layer "F.SilkS")
		)
		(fp_line
			(start -0.508 -0.9398)
			(end -0.508 0.9398)
			(stroke
				(width 0.1524)
				(type default)
			)
			(layer "F.SilkS")
		)
		(fp_rect
			(start -0.508 0.9398)
			(end 0.508 -0.9398)
			(stroke
				(width 0)
				(type default)
			)
			(fill no)
			(layer "F.CrtYd")
		)
		(fp_rect
			(start -0.508 0.9398)
			(end 0.508 -0.9398)
			(stroke
				(width 0)
				(type default)
			)
			(fill no)
			(layer "F.Fab")
		)
		(pad "1" smd custom
			(at 0 -0.4445 90)
			(size 0.1397 0.1397)
			(layers "F.Cu" "F.Mask" "F.Paste")
			(net "SW_PWR_R_HDD1")
			(options
				(clearance outline)
				(anchor circle)
			)
			(primitives
				(gr_poly
					(pts
						(arc
							(start -0.1778 -0.2794)
							(mid -0.249642 -0.249642)
							(end -0.2794 -0.1778)
						)
						(arc
							(start -0.2794 0.1778)
							(mid -0.249642 0.249642)
							(end -0.1778 0.2794)
						)
						(arc
							(start 0.1778 0.2794)
							(mid 0.249642 0.249642)
							(end 0.2794 0.1778)
						)
						(arc
							(start 0.2794 -0.1778)
							(mid 0.249642 -0.249642)
							(end 0.1778 -0.2794)
						)
					)
					(width 0)
					(fill yes)
				)
			)
		)
		(pad "2" smd custom
			(at 0 0.4445 90)
			(size 0.1397 0.1397)
			(layers "F.Cu" "F.Mask" "F.Paste")
			(net "GND")
			(options
				(clearance outline)
				(anchor circle)
			)
			(primitives
				(gr_poly
					(pts
						(arc
							(start -0.1778 -0.2794)
							(mid -0.249642 -0.249642)
							(end -0.2794 -0.1778)
						)
						(arc
							(start -0.2794 0.1778)
							(mid -0.249642 0.249642)
							(end -0.1778 0.2794)
						)
						(arc
							(start 0.1778 0.2794)
							(mid 0.249642 0.249642)
							(end 0.2794 0.1778)
						)
						(arc
							(start 0.2794 -0.1778)
							(mid 0.249642 -0.249642)
							(end 0.1778 -0.2794)
						)
					)
					(width 0)
					(fill yes)
				)
			)
		)
	)
	(footprint ""
		(layer "F.Cu")
		(at 268.224 -210.4136 90)
		(property "Reference" "R10"
			(at 0 0 90)
			(layer "F.SilkS")
			(hide yes)
			(effects
				(font
					(size 1.27 1.27)
				)
			)
		)
		(property "Value" "1KR2J-1-GP"
			(at 0.064008 -3.993896 90)
			(unlocked yes)
			(layer "F.Fab")
			(hide yes)
			(effects
				(font
					(size 1.016 1.016)
					(thickness 0.1524)
				)
			)
		)
		(property "Device Type" "R402H16"
			(at 0.064008 -5.517896 90)
			(unlocked yes)
			(layer "F.Fab")
			(hide yes)
			(effects
				(font
					(size 1.016 1.016)
					(thickness 0.1524)
				)
			)
		)
		(duplicate_pad_numbers_are_jumpers no)
		(fp_line
			(start 0.508 -0.9398)
			(end -0.508 -0.9398)
			(stroke
				(width 0.1524)
				(type default)
			)
			(layer "F.SilkS")
		)
		(fp_line
			(start -0.508 -0.9398)
			(end -0.508 0.9398)
			(stroke
				(width 0.1524)
				(type default)
			)
			(layer "F.SilkS")
		)
		(fp_rect
			(start -0.508 0.9398)
			(end 0.508 -0.9398)
			(stroke
				(width 0)
				(type default)
			)
			(fill no)
			(layer "F.CrtYd")
		)
		(fp_rect
			(start -0.508 0.9398)
			(end 0.508 -0.9398)
			(stroke
				(width 0)
				(type default)
			)
			(fill no)
			(layer "F.Fab")
		)
		(pad "1" smd custom
			(at 0 -0.4445 90)
			(size 0.1397 0.1397)
			(layers "F.Cu" "F.Mask" "F.Paste")
			(net "P3V3_STBY_B")
			(options
				(clearance outline)
				(anchor circle)
			)
			(primitives
				(gr_poly
					(pts
						(arc
							(start -0.1778 -0.2794)
							(mid -0.249642 -0.249642)
							(end -0.2794 -0.1778)
						)
						(arc
							(start -0.2794 0.1778)
							(mid -0.249642 0.249642)
							(end -0.1778 0.2794)
						)
						(arc
							(start 0.1778 0.2794)
							(mid 0.249642 0.249642)
							(end 0.2794 0.1778)
						)
						(arc
							(start 0.2794 -0.1778)
							(mid 0.249642 -0.249642)
							(end 0.1778 -0.2794)
						)
					)
					(width 0)
					(fill yes)
				)
			)
		)
		(pad "2" smd custom
			(at 0 0.4445 90)
			(size 0.1397 0.1397)
			(layers "F.Cu" "F.Mask" "F.Paste")
			(net "I2C_DRIVE_B_INS_SCL")
			(options
				(clearance outline)
				(anchor circle)
			)
			(primitives
				(gr_poly
					(pts
						(arc
							(start -0.1778 -0.2794)
							(mid -0.249642 -0.249642)
							(end -0.2794 -0.1778)
						)
						(arc
							(start -0.2794 0.1778)
							(mid -0.249642 0.249642)
							(end -0.1778 0.2794)
						)
						(arc
							(start 0.1778 0.2794)
							(mid 0.249642 0.249642)
							(end 0.2794 0.1778)
						)
						(arc
							(start 0.2794 -0.1778)
							(mid 0.249642 -0.249642)
							(end 0.1778 -0.2794)
						)
					)
					(width 0)
					(fill yes)
				)
			)
		)
	)
	(footprint ""
		(layer "F.Cu")
		(at 135.9408 -369.4684 180)
		(property "Reference" "D40"
			(at 0 0 180)
			(layer "F.SilkS")
			(hide yes)
			(effects
				(font
					(size 1.27 1.27)
				)
			)
		)
		(property "Value" "BAS16H-GP"
			(at 0 -5.5372 180)
			(unlocked yes)
			(layer "F.Fab")
			(hide yes)
			(effects
				(font
					(size 1.016 1.016)
					(thickness 0.1524)
				)
			)
		)
		(property "Device Type" "SOD123AKH48"
			(at 0 -7.0612 180)
			(unlocked yes)
			(layer "F.Fab")
			(hide yes)
			(effects
				(font
					(size 1.016 1.016)
					(thickness 0.1524)
				)
			)
		)
		(duplicate_pad_numbers_are_jumpers no)
		(fp_line
			(start 1.016 2.667)
			(end 1.016 -2.667)
			(stroke
				(width 0.1524)
				(type default)
			)
			(layer "F.SilkS")
		)
		(fp_line
			(start 1.016 -2.667)
			(end -1.016 -2.667)
			(stroke
				(width 0.1524)
				(type default)
			)
			(layer "F.SilkS")
		)
		(fp_line
			(start 0.889 2.921)
			(end -0.889 2.921)
			(stroke
				(width 0.508)
				(type default)
			)
			(layer "F.SilkS")
		)
		(fp_line
			(start -1.016 2.667)
			(end 1.016 2.667)
			(stroke
				(width 0.1524)
				(type default)
			)
			(layer "F.SilkS")
		)
		(fp_line
			(start -1.016 -2.667)
			(end -1.016 2.667)
			(stroke
				(width 0.1524)
				(type default)
			)
			(layer "F.SilkS")
		)
		(fp_rect
			(start -1.143 3.175)
			(end 1.143 -2.794)
			(stroke
				(width 0)
				(type default)
			)
			(fill no)
			(layer "F.CrtYd")
		)
		(fp_poly
			(pts
				(xy -1.143 -2.794) (xy 1.143 -2.794) (xy 1.143 3.175) (xy -1.143 3.175)
			)
			(stroke
				(width 0)
				(type default)
			)
			(fill no)
			(layer "F.Fab")
		)
		(pad "A" smd rect
			(at 0 -1.6891 180)
			(size 0.889 1.397)
			(layers "F.Cu" "F.Mask" "F.Paste")
			(net "FAN_1_TACH1")
		)
		(pad "K" smd rect
			(at 0 1.6891 180)
			(size 0.889 1.397)
			(layers "F.Cu" "F.Mask" "F.Paste")
			(net "P12V_IN")
		)
	)
	(footprint ""
		(layer "F.Cu")
		(at 174.498 -138.049 90)
		(property "Reference" "R468"
			(at 0 0 90)
			(layer "F.SilkS")
			(hide yes)
			(effects
				(font
					(size 1.27 1.27)
				)
			)
		)
		(property "Value" "4K7R2J-2-GP"
			(at 0.064008 -3.993896 90)
			(unlocked yes)
			(layer "F.Fab")
			(hide yes)
			(effects
				(font
					(size 1.016 1.016)
					(thickness 0.1524)
				)
			)
		)
		(property "Device Type" "R402H16"
			(at 0.064008 -5.517896 90)
			(unlocked yes)
			(layer "F.Fab")
			(hide yes)
			(effects
				(font
					(size 1.016 1.016)
					(thickness 0.1524)
				)
			)
		)
		(duplicate_pad_numbers_are_jumpers no)
		(fp_line
			(start 0.508 -0.9398)
			(end -0.508 -0.9398)
			(stroke
				(width 0.1524)
				(type default)
			)
			(layer "F.SilkS")
		)
		(fp_line
			(start -0.508 -0.9398)
			(end -0.508 0.9398)
			(stroke
				(width 0.1524)
				(type default)
			)
			(layer "F.SilkS")
		)
		(fp_rect
			(start -0.508 0.9398)
			(end 0.508 -0.9398)
			(stroke
				(width 0)
				(type default)
			)
			(fill no)
			(layer "F.CrtYd")
		)
		(fp_rect
			(start -0.508 0.9398)
			(end 0.508 -0.9398)
			(stroke
				(width 0)
				(type default)
			)
			(fill no)
			(layer "F.Fab")
		)
		(pad "1" smd custom
			(at 0 -0.4445 90)
			(size 0.1397 0.1397)
			(layers "F.Cu" "F.Mask" "F.Paste")
			(net "P12V_B")
			(options
				(clearance outline)
				(anchor circle)
			)
			(primitives
				(gr_poly
					(pts
						(arc
							(start -0.1778 -0.2794)
							(mid -0.249642 -0.249642)
							(end -0.2794 -0.1778)
						)
						(arc
							(start -0.2794 0.1778)
							(mid -0.249642 0.249642)
							(end -0.1778 0.2794)
						)
						(arc
							(start 0.1778 0.2794)
							(mid 0.249642 0.249642)
							(end 0.2794 0.1778)
						)
						(arc
							(start 0.2794 -0.1778)
							(mid 0.249642 -0.249642)
							(end 0.1778 -0.2794)
						)
					)
					(width 0)
					(fill yes)
				)
			)
		)
		(pad "2" smd custom
			(at 0 0.4445 90)
			(size 0.1397 0.1397)
			(layers "F.Cu" "F.Mask" "F.Paste")
			(net "SW_HDD_P17")
			(options
				(clearance outline)
				(anchor circle)
			)
			(primitives
				(gr_poly
					(pts
						(arc
							(start -0.1778 -0.2794)
							(mid -0.249642 -0.249642)
							(end -0.2794 -0.1778)
						)
						(arc
							(start -0.2794 0.1778)
							(mid -0.249642 0.249642)
							(end -0.1778 0.2794)
						)
						(arc
							(start 0.1778 0.2794)
							(mid 0.249642 0.249642)
							(end 0.2794 0.1778)
						)
						(arc
							(start 0.2794 -0.1778)
							(mid 0.249642 -0.249642)
							(end 0.1778 -0.2794)
						)
					)
					(width 0)
					(fill yes)
				)
			)
		)
	)
)
